(kicad_pcb
	(version 20260206)
	(generator "pcbnew")
	(generator_version "10.0")
	(general
		(thickness 1.6)
		(legacy_teardrops no)
	)
	(paper "A4")
	(title_block
		(title "peb — Lightning_PEB_BRD.brd")
		(comment 1 "Lightning (Wiwynn / Facebook NVMe JBOF) / footprints 601-608 of 2563")
	)
	(layers
		(0 "F.Cu" signal "TOP")
		(4 "In1.Cu" signal "L2GND")
		(6 "In2.Cu" signal "L3")
		(8 "In3.Cu" signal "L4VCC")
		(10 "In4.Cu" signal "L5VCC")
		(12 "In5.Cu" signal "L6")
		(14 "In6.Cu" signal "L7GND")
		(2 "B.Cu" signal "BOTTOM")
		(9 "F.Adhes" user "F.Adhesive")
		(11 "B.Adhes" user "B.Adhesive")
		(13 "F.Paste" user "Package Geometry/Pastemask Top")
		(15 "B.Paste" user "Package Geometry/Pastemask Bottom")
		(5 "F.SilkS" user "Ref Des/Silkscreen Top")
		(7 "B.SilkS" user "Ref Des/Silkscreen Bottom")
		(1 "F.Mask" user "Board Geometry/Soldermask Top")
		(3 "B.Mask" user "Board Geometry/Soldermask Bottom")
		(17 "Dwgs.User" user "User.Drawings")
		(19 "Cmts.User" user "User.Comments")
		(21 "Eco1.User" user "User.Eco1")
		(23 "Eco2.User" user "User.Eco2")
		(25 "Edge.Cuts" user "Board Geometry/Outline")
		(27 "Margin" user)
		(31 "F.CrtYd" user "Package Geometry/Place Bound Top")
		(29 "B.CrtYd" user "Package Geometry/Place Bound Bottom")
		(35 "F.Fab" user "Ref Des/Assembly Top")
		(33 "B.Fab" user "Ref Des/Assembly Bottom")
	)
	(footprint ""
		(layer "F.Cu")
		(at 218.797124 -190.601092 180)
		(property "Reference" "R550"
			(at 0 0 180)
			(layer "F.SilkS")
			(hide yes)
			(effects
				(font
					(size 1.27 1.27)
				)
			)
		)
		(property "Value" "10KR2F-2-GP"
			(at 0.064008 -3.993896 180)
			(unlocked yes)
			(layer "F.Fab")
			(hide yes)
			(effects
				(font
					(size 1.016 1.016)
					(thickness 0.1524)
				)
			)
		)
		(property "Device Type" "R402H16"
			(at 0.064008 -5.517896 180)
			(unlocked yes)
			(layer "F.Fab")
			(hide yes)
			(effects
				(font
					(size 1.016 1.016)
					(thickness 0.1524)
				)
			)
		)
		(duplicate_pad_numbers_are_jumpers no)
		(fp_line
			(start 0.508 -0.9398)
			(end -0.508 -0.9398)
			(stroke
				(width 0.1524)
				(type default)
			)
			(layer "F.SilkS")
		)
		(fp_line
			(start -0.508 -0.9398)
			(end -0.508 0.9398)
			(stroke
				(width 0.1524)
				(type default)
			)
			(layer "F.SilkS")
		)
		(fp_rect
			(start -0.508 0.9398)
			(end 0.508 -0.9398)
			(stroke
				(width 0)
				(type default)
			)
			(fill no)
			(layer "F.CrtYd")
		)
		(fp_rect
			(start -0.508 0.9398)
			(end 0.508 -0.9398)
			(stroke
				(width 0)
				(type default)
			)
			(fill no)
			(layer "F.Fab")
		)
		(pad "1" smd custom
			(at 0 -0.4445 180)
			(size 0.1397 0.1397)
			(layers "F.Cu" "F.Mask" "F.Paste")
			(net "GND")
			(options
				(clearance outline)
				(anchor circle)
			)
			(primitives
				(gr_poly
					(pts
						(arc
							(start -0.1778 -0.2794)
							(mid -0.249642 -0.249642)
							(end -0.2794 -0.1778)
						)
						(arc
							(start -0.2794 0.1778)
							(mid -0.249642 0.249642)
							(end -0.1778 0.2794)
						)
						(arc
							(start 0.1778 0.2794)
							(mid 0.249642 0.249642)
							(end 0.2794 0.1778)
						)
						(arc
							(start 0.2794 -0.1778)
							(mid 0.249642 -0.249642)
							(end 0.1778 -0.2794)
						)
					)
					(width 0)
					(fill yes)
				)
			)
		)
		(pad "2" smd custom
			(at 0 0.4445 180)
			(size 0.1397 0.1397)
			(layers "F.Cu" "F.Mask" "F.Paste")
			(net "IOEXP3_AD2")
			(options
				(clearance outline)
				(anchor circle)
			)
			(primitives
				(gr_poly
					(pts
						(arc
							(start -0.1778 -0.2794)
							(mid -0.249642 -0.249642)
							(end -0.2794 -0.1778)
						)
						(arc
							(start -0.2794 0.1778)
							(mid -0.249642 0.249642)
							(end -0.1778 0.2794)
						)
						(arc
							(start 0.1778 0.2794)
							(mid 0.249642 0.249642)
							(end 0.2794 0.1778)
						)
						(arc
							(start 0.2794 -0.1778)
							(mid 0.249642 -0.249642)
							(end 0.1778 -0.2794)
						)
					)
					(width 0)
					(fill yes)
				)
			)
		)
	)
	(footprint ""
		(layer "F.Cu")
		(at 183.0578 -4.23418)
		(property "Reference" "R2951"
			(at 0 0 0)
			(layer "F.SilkS")
			(hide yes)
			(effects
				(font
					(size 1.27 1.27)
				)
			)
		)
		(property "Value" "0R2J-2-GP"
			(at 0.064008 -3.993896 0)
			(unlocked yes)
			(layer "F.Fab")
			(hide yes)
			(effects
				(font
					(size 1.016 1.016)
					(thickness 0.1524)
				)
			)
		)
		(property "Device Type" "R402H16"
			(at 0.064008 -5.517896 0)
			(unlocked yes)
			(layer "F.Fab")
			(hide yes)
			(effects
				(font
					(size 1.016 1.016)
					(thickness 0.1524)
				)
			)
		)
		(duplicate_pad_numbers_are_jumpers no)
		(fp_line
			(start -0.508 -0.9398)
			(end -0.508 0.9398)
			(stroke
				(width 0.1524)
				(type default)
			)
			(layer "F.SilkS")
		)
		(fp_line
			(start 0.508 -0.9398)
			(end -0.508 -0.9398)
			(stroke
				(width 0.1524)
				(type default)
			)
			(layer "F.SilkS")
		)
		(fp_rect
			(start -0.508 0.9398)
			(end 0.508 -0.9398)
			(stroke
				(width 0)
				(type default)
			)
			(fill no)
			(layer "F.CrtYd")
		)
		(fp_rect
			(start -0.508 0.9398)
			(end 0.508 -0.9398)
			(stroke
				(width 0)
				(type default)
			)
			(fill no)
			(layer "F.Fab")
		)
		(pad "1" smd custom
			(at 0 -0.4445)
			(size 0.1397 0.1397)
			(layers "F.Cu" "F.Mask" "F.Paste")
			(net "HOST3_RST_N")
			(options
				(clearance outline)
				(anchor circle)
			)
			(primitives
				(gr_poly
					(pts
						(arc
							(start -0.1778 -0.2794)
							(mid -0.249642 -0.249642)
							(end -0.2794 -0.1778)
						)
						(arc
							(start -0.2794 0.1778)
							(mid -0.249642 0.249642)
							(end -0.1778 0.2794)
						)
						(arc
							(start 0.1778 0.2794)
							(mid 0.249642 0.249642)
							(end 0.2794 0.1778)
						)
						(arc
							(start 0.2794 -0.1778)
							(mid 0.249642 -0.249642)
							(end 0.1778 -0.2794)
						)
					)
					(width 0)
					(fill yes)
				)
			)
		)
		(pad "2" smd custom
			(at 0 0.4445)
			(size 0.1397 0.1397)
			(layers "F.Cu" "F.Mask" "F.Paste")
			(net "HOST3_RST_N_C")
			(options
				(clearance outline)
				(anchor circle)
			)
			(primitives
				(gr_poly
					(pts
						(arc
							(start -0.1778 -0.2794)
							(mid -0.249642 -0.249642)
							(end -0.2794 -0.1778)
						)
						(arc
							(start -0.2794 0.1778)
							(mid -0.249642 0.249642)
							(end -0.1778 0.2794)
						)
						(arc
							(start 0.1778 0.2794)
							(mid 0.249642 0.249642)
							(end 0.2794 0.1778)
						)
						(arc
							(start 0.2794 -0.1778)
							(mid 0.249642 -0.249642)
							(end 0.1778 -0.2794)
						)
					)
					(width 0)
					(fill yes)
				)
			)
		)
	)
	(footprint ""
		(layer "F.Cu")
		(at 23.876 -133.731 90)
		(property "Reference" "R343"
			(at 0 0 90)
			(layer "F.SilkS")
			(hide yes)
			(effects
				(font
					(size 1.27 1.27)
				)
			)
		)
		(property "Value" "3K3R2F-2-GP"
			(at 0.064008 -3.993896 90)
			(unlocked yes)
			(layer "F.Fab")
			(hide yes)
			(effects
				(font
					(size 1.016 1.016)
					(thickness 0.1524)
				)
			)
		)
		(property "Device Type" "R402H16"
			(at 0.064008 -5.517896 90)
			(unlocked yes)
			(layer "F.Fab")
			(hide yes)
			(effects
				(font
					(size 1.016 1.016)
					(thickness 0.1524)
				)
			)
		)
		(duplicate_pad_numbers_are_jumpers no)
		(fp_line
			(start 0.508 -0.9398)
			(end -0.508 -0.9398)
			(stroke
				(width 0.1524)
				(type default)
			)
			(layer "F.SilkS")
		)
		(fp_line
			(start -0.508 -0.9398)
			(end -0.508 0.9398)
			(stroke
				(width 0.1524)
				(type default)
			)
			(layer "F.SilkS")
		)
		(fp_rect
			(start -0.508 0.9398)
			(end 0.508 -0.9398)
			(stroke
				(width 0)
				(type default)
			)
			(fill no)
			(layer "F.CrtYd")
		)
		(fp_rect
			(start -0.508 0.9398)
			(end 0.508 -0.9398)
			(stroke
				(width 0)
				(type default)
			)
			(fill no)
			(layer "F.Fab")
		)
		(pad "1" smd custom
			(at 0 -0.4445 90)
			(size 0.1397 0.1397)
			(layers "F.Cu" "F.Mask" "F.Paste")
			(net "P3V3_STBY")
			(options
				(clearance outline)
				(anchor circle)
			)
			(primitives
				(gr_poly
					(pts
						(arc
							(start -0.1778 -0.2794)
							(mid -0.249642 -0.249642)
							(end -0.2794 -0.1778)
						)
						(arc
							(start -0.2794 0.1778)
							(mid -0.249642 0.249642)
							(end -0.1778 0.2794)
						)
						(arc
							(start 0.1778 0.2794)
							(mid 0.249642 0.249642)
							(end 0.2794 0.1778)
						)
						(arc
							(start 0.2794 -0.1778)
							(mid 0.249642 -0.249642)
							(end 0.1778 -0.2794)
						)
					)
					(width 0)
					(fill yes)
				)
			)
		)
		(pad "2" smd custom
			(at 0 0.4445 90)
			(size 0.1397 0.1397)
			(layers "F.Cu" "F.Mask" "F.Paste")
			(net "ROMA1")
			(options
				(clearance outline)
				(anchor circle)
			)
			(primitives
				(gr_poly
					(pts
						(arc
							(start -0.1778 -0.2794)
							(mid -0.249642 -0.249642)
							(end -0.2794 -0.1778)
						)
						(arc
							(start -0.2794 0.1778)
							(mid -0.249642 0.249642)
							(end -0.1778 0.2794)
						)
						(arc
							(start 0.1778 0.2794)
							(mid 0.249642 0.249642)
							(end 0.2794 0.1778)
						)
						(arc
							(start 0.2794 -0.1778)
							(mid 0.249642 -0.249642)
							(end 0.1778 -0.2794)
						)
					)
					(width 0)
					(fill yes)
				)
			)
		)
	)
	(footprint ""
		(layer "F.Cu")
		(at 11.654028 -72.933814 -90)
		(property "Reference" "TP157"
			(at 0 0 270)
			(layer "F.SilkS")
			(hide yes)
			(effects
				(font
					(size 1.27 1.27)
				)
			)
		)
		(property "Value" "TPAD28-2-GP"
			(at -0.0127 -1.6637 270)
			(unlocked yes)
			(layer "F.Fab")
			(hide yes)
			(effects
				(font
					(size 1.016 1.016)
					(thickness 0.1524)
				)
			)
		)
		(property "Device Type" "TPAD28"
			(at -0.0127 -3.1877 270)
			(unlocked yes)
			(layer "F.Fab")
			(hide yes)
			(effects
				(font
					(size 1.016 1.016)
					(thickness 0.1524)
				)
			)
		)
		(duplicate_pad_numbers_are_jumpers no)
		(fp_poly
			(pts
				(arc
					(start 0 -0.3556)
					(mid 0 0.3556)
					(end 0 -0.3556)
				)
			)
			(stroke
				(width 0)
				(type default)
			)
			(fill no)
			(layer "F.CrtYd")
		)
		(fp_poly
			(pts
				(arc
					(start 0 -0.6096)
					(mid 0 0.6096)
					(end 0 -0.6096)
				)
			)
			(stroke
				(width 0)
				(type default)
			)
			(fill no)
			(layer "F.Fab")
		)
		(pad "1" smd circle
			(at 0 0 270)
			(size 0.7112 0.7112)
			(layers "F.Cu" "F.Mask" "F.Paste")
			(net "NCSI_ARB_OUT")
		)
	)
	(footprint ""
		(layer "F.Cu")
		(at 330.835 -86.487)
		(property "Reference" "R4174"
			(at 0 0 0)
			(layer "F.SilkS")
			(hide yes)
			(effects
				(font
					(size 1.27 1.27)
				)
			)
		)
		(property "Value" "4K7R2F-GP"
			(at 0.064008 -3.993896 0)
			(unlocked yes)
			(layer "F.Fab")
			(hide yes)
			(effects
				(font
					(size 1.016 1.016)
					(thickness 0.1524)
				)
			)
		)
		(property "Device Type" "R402H16"
			(at 0.064008 -5.517896 0)
			(unlocked yes)
			(layer "F.Fab")
			(hide yes)
			(effects
				(font
					(size 1.016 1.016)
					(thickness 0.1524)
				)
			)
		)
		(duplicate_pad_numbers_are_jumpers no)
		(fp_line
			(start -0.508 -0.9398)
			(end -0.508 0.9398)
			(stroke
				(width 0.1524)
				(type default)
			)
			(layer "F.SilkS")
		)
		(fp_line
			(start 0.508 -0.9398)
			(end -0.508 -0.9398)
			(stroke
				(width 0.1524)
				(type default)
			)
			(layer "F.SilkS")
		)
		(fp_rect
			(start -0.508 0.9398)
			(end 0.508 -0.9398)
			(stroke
				(width 0)
				(type default)
			)
			(fill no)
			(layer "F.CrtYd")
		)
		(fp_rect
			(start -0.508 0.9398)
			(end 0.508 -0.9398)
			(stroke
				(width 0)
				(type default)
			)
			(fill no)
			(layer "F.Fab")
		)
		(pad "1" smd custom
			(at 0 -0.4445)
			(size 0.1397 0.1397)
			(layers "F.Cu" "F.Mask" "F.Paste")
			(net "UPLINK8")
			(options
				(clearance outline)
				(anchor circle)
			)
			(primitives
				(gr_poly
					(pts
						(arc
							(start -0.1778 -0.2794)
							(mid -0.249642 -0.249642)
							(end -0.2794 -0.1778)
						)
						(arc
							(start -0.2794 0.1778)
							(mid -0.249642 0.249642)
							(end -0.1778 0.2794)
						)
						(arc
							(start 0.1778 0.2794)
							(mid 0.249642 0.249642)
							(end 0.2794 0.1778)
						)
						(arc
							(start 0.2794 -0.1778)
							(mid 0.249642 -0.249642)
							(end 0.1778 -0.2794)
						)
					)
					(width 0)
					(fill yes)
				)
			)
		)
		(pad "2" smd custom
			(at 0 0.4445)
			(size 0.1397 0.1397)
			(layers "F.Cu" "F.Mask" "F.Paste")
			(net "P3V3_STBY")
			(options
				(clearance outline)
				(anchor circle)
			)
			(primitives
				(gr_poly
					(pts
						(arc
							(start -0.1778 -0.2794)
							(mid -0.249642 -0.249642)
							(end -0.2794 -0.1778)
						)
						(arc
							(start -0.2794 0.1778)
							(mid -0.249642 0.249642)
							(end -0.1778 0.2794)
						)
						(arc
							(start 0.1778 0.2794)
							(mid 0.249642 0.249642)
							(end 0.2794 0.1778)
						)
						(arc
							(start 0.2794 -0.1778)
							(mid 0.249642 -0.249642)
							(end 0.1778 -0.2794)
						)
					)
					(width 0)
					(fill yes)
				)
			)
		)
	)
	(footprint ""
		(layer "F.Cu")
		(at 17.653 -111.379 90)
		(property "Reference" "PC79"
			(at 0 0 90)
			(layer "F.SilkS")
			(hide yes)
			(effects
				(font
					(size 1.27 1.27)
				)
			)
		)
		(property "Value" "SC22U6D3V5MX-5-GP"
			(at -0.0762 -6.1214 90)
			(unlocked yes)
			(layer "F.Fab")
			(hide yes)
			(effects
				(font
					(size 1.016 1.016)
					(thickness 0.1524)
				)
			)
		)
		(property "Device Type" "C805H56"
			(at -0.0762 -8.1534 90)
			(unlocked yes)
			(layer "F.Fab")
			(hide yes)
			(effects
				(font
					(size 1.016 1.016)
					(thickness 0.1524)
				)
			)
		)
		(duplicate_pad_numbers_are_jumpers no)
		(fp_line
			(start 0.635 0)
			(end -0.635 0)
			(stroke
				(width 0.508)
				(type default)
			)
			(layer "F.SilkS")
		)
		(fp_rect
			(start -0.9652 1.778)
			(end 0.9652 -1.778)
			(stroke
				(width 0)
				(type default)
			)
			(fill no)
			(layer "F.CrtYd")
		)
		(fp_poly
			(pts
				(xy -0.9652 -1.778) (xy 0.9652 -1.778) (xy 0.9652 1.778) (xy -0.9652 1.778)
			)
			(stroke
				(width 0)
				(type default)
			)
			(fill no)
			(layer "F.Fab")
		)
		(pad "1" smd rect
			(at 0 -0.9652 90)
			(size 1.397 1.143)
			(layers "F.Cu" "F.Mask" "F.Paste")
			(net "P1V26_PWR")
		)
		(pad "2" smd rect
			(at 0 0.9652 90)
			(size 1.397 1.143)
			(layers "F.Cu" "F.Mask" "F.Paste")
			(net "GND")
		)
	)
	(footprint ""
		(layer "F.Cu")
		(at 26.415492 -87.0077)
		(property "Reference" "R372"
			(at 0 0 0)
			(layer "F.SilkS")
			(hide yes)
			(effects
				(font
					(size 1.27 1.27)
				)
			)
		)
		(property "Value" "0R2J-2-GP"
			(at 0.064008 -3.993896 0)
			(unlocked yes)
			(layer "F.Fab")
			(hide yes)
			(effects
				(font
					(size 1.016 1.016)
					(thickness 0.1524)
				)
			)
		)
		(property "Device Type" "R402H16"
			(at 0.064008 -5.517896 0)
			(unlocked yes)
			(layer "F.Fab")
			(hide yes)
			(effects
				(font
					(size 1.016 1.016)
					(thickness 0.1524)
				)
			)
		)
		(duplicate_pad_numbers_are_jumpers no)
		(fp_line
			(start -0.508 -0.9398)
			(end -0.508 0.9398)
			(stroke
				(width 0.1524)
				(type default)
			)
			(layer "F.SilkS")
		)
		(fp_line
			(start 0.508 -0.9398)
			(end -0.508 -0.9398)
			(stroke
				(width 0.1524)
				(type default)
			)
			(layer "F.SilkS")
		)
		(fp_rect
			(start -0.508 0.9398)
			(end 0.508 -0.9398)
			(stroke
				(width 0)
				(type default)
			)
			(fill no)
			(layer "F.CrtYd")
		)
		(fp_rect
			(start -0.508 0.9398)
			(end 0.508 -0.9398)
			(stroke
				(width 0)
				(type default)
			)
			(fill no)
			(layer "F.Fab")
		)
		(pad "1" smd custom
			(at 0 -0.4445)
			(size 0.1397 0.1397)
			(layers "F.Cu" "F.Mask" "F.Paste")
			(net "I210_PERST_N")
			(options
				(clearance outline)
				(anchor circle)
			)
			(primitives
				(gr_poly
					(pts
						(arc
							(start -0.1778 -0.2794)
							(mid -0.249642 -0.249642)
							(end -0.2794 -0.1778)
						)
						(arc
							(start -0.2794 0.1778)
							(mid -0.249642 0.249642)
							(end -0.1778 0.2794)
						)
						(arc
							(start 0.1778 0.2794)
							(mid 0.249642 0.249642)
							(end 0.2794 0.1778)
						)
						(arc
							(start 0.2794 -0.1778)
							(mid 0.249642 -0.249642)
							(end 0.1778 -0.2794)
						)
					)
					(width 0)
					(fill yes)
				)
			)
		)
		(pad "2" smd custom
			(at 0 0.4445)
			(size 0.1397 0.1397)
			(layers "F.Cu" "F.Mask" "F.Paste")
			(net "PHY_RESET_N")
			(options
				(clearance outline)
				(anchor circle)
			)
			(primitives
				(gr_poly
					(pts
						(arc
							(start -0.1778 -0.2794)
							(mid -0.249642 -0.249642)
							(end -0.2794 -0.1778)
						)
						(arc
							(start -0.2794 0.1778)
							(mid -0.249642 0.249642)
							(end -0.1778 0.2794)
						)
						(arc
							(start 0.1778 0.2794)
							(mid 0.249642 0.249642)
							(end 0.2794 0.1778)
						)
						(arc
							(start 0.2794 -0.1778)
							(mid 0.249642 -0.249642)
							(end 0.1778 -0.2794)
						)
					)
					(width 0)
					(fill yes)
				)
			)
		)
	)
	(footprint ""
		(layer "F.Cu")
		(at 331.216 -3.683)
		(property "Reference" "SR713"
			(at 0 0 0)
			(layer "F.SilkS")
			(hide yes)
			(effects
				(font
					(size 1.27 1.27)
				)
			)
		)
		(property "Value" "150R2F-1-GP"
			(at 0.064008 -3.993896 0)
			(unlocked yes)
			(layer "F.Fab")
			(hide yes)
			(effects
				(font
					(size 1.016 1.016)
					(thickness 0.1524)
				)
			)
		)
		(property "Device Type" "R402H16"
			(at 0.064008 -5.517896 0)
			(unlocked yes)
			(layer "F.Fab")
			(hide yes)
			(effects
				(font
					(size 1.016 1.016)
					(thickness 0.1524)
				)
			)
		)
		(duplicate_pad_numbers_are_jumpers no)
		(fp_line
			(start -0.508 -0.9398)
			(end -0.508 0.9398)
			(stroke
				(width 0.1524)
				(type default)
			)
			(layer "F.SilkS")
		)
		(fp_line
			(start 0.508 -0.9398)
			(end -0.508 -0.9398)
			(stroke
				(width 0.1524)
				(type default)
			)
			(layer "F.SilkS")
		)
		(fp_rect
			(start -0.508 0.9398)
			(end 0.508 -0.9398)
			(stroke
				(width 0)
				(type default)
			)
			(fill no)
			(layer "F.CrtYd")
		)
		(fp_rect
			(start -0.508 0.9398)
			(end 0.508 -0.9398)
			(stroke
				(width 0)
				(type default)
			)
			(fill no)
			(layer "F.Fab")
		)
		(pad "1" smd custom
			(at 0 -0.4445)
			(size 0.1397 0.1397)
			(layers "F.Cu" "F.Mask" "F.Paste")
			(net "P3V3_STBY")
			(options
				(clearance outline)
				(anchor circle)
			)
			(primitives
				(gr_poly
					(pts
						(arc
							(start -0.1778 -0.2794)
							(mid -0.249642 -0.249642)
							(end -0.2794 -0.1778)
						)
						(arc
							(start -0.2794 0.1778)
							(mid -0.249642 0.249642)
							(end -0.1778 0.2794)
						)
						(arc
							(start 0.1778 0.2794)
							(mid 0.249642 0.249642)
							(end 0.2794 0.1778)
						)
						(arc
							(start 0.2794 -0.1778)
							(mid 0.249642 -0.249642)
							(end 0.1778 -0.2794)
						)
					)
					(width 0)
					(fill yes)
				)
			)
		)
		(pad "2" smd custom
			(at 0 0.4445)
			(size 0.1397 0.1397)
			(layers "F.Cu" "F.Mask" "F.Paste")
			(net "LED_R_8")
			(options
				(clearance outline)
				(anchor circle)
			)
			(primitives
				(gr_poly
					(pts
						(arc
							(start -0.1778 -0.2794)
							(mid -0.249642 -0.249642)
							(end -0.2794 -0.1778)
						)
						(arc
							(start -0.2794 0.1778)
							(mid -0.249642 0.249642)
							(end -0.1778 0.2794)
						)
						(arc
							(start 0.1778 0.2794)
							(mid 0.249642 0.249642)
							(end 0.2794 0.1778)
						)
						(arc
							(start 0.2794 -0.1778)
							(mid 0.249642 -0.249642)
							(end 0.1778 -0.2794)
						)
					)
					(width 0)
					(fill yes)
				)
			)
		)
	)
)
